(kicad_pcb
	(version 20260206)
	(generator "pcbnew")
	(generator_version "10.0")
	(general
		(thickness 1.6)
		(legacy_teardrops no)
	)
	(paper "A4")
	(title_block
		(title "01162023_DA0F0TEBIF0_F0T_Expander_BD_F_brd_V02_OCP.brd")
		(comment 1 "Grand Teton / footprints 65-71 of 9728")
	)
	(layers
		(0 "F.Cu" signal "TOP")
		(4 "In1.Cu" signal "GND")
		(6 "In2.Cu" signal "VCC")
		(8 "In3.Cu" signal "VCC1")
		(10 "In4.Cu" signal "GND1")
		(12 "In5.Cu" signal "IN1")
		(14 "In6.Cu" signal "GND2")
		(16 "In7.Cu" signal "IN2")
		(18 "In8.Cu" signal "GND3")
		(20 "In9.Cu" signal "IN3")
		(22 "In10.Cu" signal "GND4")
		(24 "In11.Cu" signal "IN4")
		(26 "In12.Cu" signal "GND5")
		(28 "In13.Cu" signal "IN5")
		(30 "In14.Cu" signal "GND6")
		(32 "In15.Cu" signal "IN6")
		(34 "In16.Cu" signal "GND7")
		(2 "B.Cu" signal "BOTTOM")
		(9 "F.Adhes" user "F.Adhesive")
		(11 "B.Adhes" user "B.Adhesive")
		(13 "F.Paste" user "Package Geometry/Pastemask Top")
		(15 "B.Paste" user "Package Geometry/Pastemask Bottom")
		(5 "F.SilkS" user "Ref Des/Silkscreen Top")
		(7 "B.SilkS" user "Ref Des/Silkscreen Bottom")
		(1 "F.Mask" user "Board Geometry/Soldermask Top")
		(3 "B.Mask" user "Board Geometry/Soldermask Bottom")
		(17 "Dwgs.User" user "User.Drawings")
		(19 "Cmts.User" user "User.Comments")
		(21 "Eco1.User" user "User.Eco1")
		(23 "Eco2.User" user "User.Eco2")
		(25 "Edge.Cuts" user "Board Geometry/Outline")
		(27 "Margin" user)
		(31 "F.CrtYd" user "Package Geometry/Place Bound Top")
		(29 "B.CrtYd" user "Package Geometry/Place Bound Bottom")
		(35 "F.Fab" user "Ref Des/Assembly Top")
		(33 "B.Fab" user "Ref Des/Assembly Bottom")
	)
	(footprint ""
		(layer "F.Cu")
		(at 113.432082 -280.44902 -90)
		(property "Reference" "PR104"
			(at 0 0 270)
			(layer "F.SilkS")
			(hide yes)
			(effects
				(font
					(size 1.27 1.27)
				)
			)
		)
		(property "Value" ""
			(at 0 0 270)
			(layer "F.Fab")
			(effects
				(font
					(size 1.27 1.27)
				)
			)
		)
		(duplicate_pad_numbers_are_jumpers no)
		(fp_line
			(start -0.7874 0.4064)
			(end -0.7874 -0.4064)
			(stroke
				(width 0.1524)
				(type default)
			)
			(layer "F.SilkS")
		)
		(fp_line
			(start 0.7874 0.4064)
			(end -0.7874 0.4064)
			(stroke
				(width 0.1524)
				(type default)
			)
			(layer "F.SilkS")
		)
		(fp_line
			(start -0.7874 -0.4064)
			(end 0.7874 -0.4064)
			(stroke
				(width 0.1524)
				(type default)
			)
			(layer "F.SilkS")
		)
		(fp_line
			(start 0.7874 -0.4064)
			(end 0.7874 0.4064)
			(stroke
				(width 0.1524)
				(type default)
			)
			(layer "F.SilkS")
		)
		(fp_line
			(start -0.67945 0.3048)
			(end -0.67945 -0.305054)
			(stroke
				(width 0.1)
				(type default)
			)
			(layer "F.Fab")
		)
		(fp_line
			(start -0.12065 0.3048)
			(end -0.67945 0.3048)
			(stroke
				(width 0.1)
				(type default)
			)
			(layer "F.Fab")
		)
		(fp_line
			(start 0.120396 0.3048)
			(end 0.120396 0.2794)
			(stroke
				(width 0.1)
				(type default)
			)
			(layer "F.Fab")
		)
		(fp_line
			(start 0.67945 0.3048)
			(end 0.120396 0.3048)
			(stroke
				(width 0.1)
				(type default)
			)
			(layer "F.Fab")
		)
		(fp_line
			(start -0.12065 0.2794)
			(end -0.12065 0.3048)
			(stroke
				(width 0.1)
				(type default)
			)
			(layer "F.Fab")
		)
		(fp_line
			(start 0.120396 0.2794)
			(end -0.12065 0.2794)
			(stroke
				(width 0.1)
				(type default)
			)
			(layer "F.Fab")
		)
		(fp_line
			(start -0.12065 -0.2794)
			(end 0.12065 -0.2794)
			(stroke
				(width 0.1)
				(type default)
			)
			(layer "F.Fab")
		)
		(fp_line
			(start 0.12065 -0.2794)
			(end 0.12065 -0.3048)
			(stroke
				(width 0.1)
				(type default)
			)
			(layer "F.Fab")
		)
		(fp_line
			(start 0.12065 -0.3048)
			(end 0.67945 -0.3048)
			(stroke
				(width 0.1)
				(type default)
			)
			(layer "F.Fab")
		)
		(fp_line
			(start 0.67945 -0.3048)
			(end 0.67945 0.3048)
			(stroke
				(width 0.1)
				(type default)
			)
			(layer "F.Fab")
		)
		(fp_line
			(start -0.67945 -0.305054)
			(end -0.12065 -0.305054)
			(stroke
				(width 0.1)
				(type default)
			)
			(layer "F.Fab")
		)
		(fp_line
			(start -0.12065 -0.305054)
			(end -0.12065 -0.2794)
			(stroke
				(width 0.1)
				(type default)
			)
			(layer "F.Fab")
		)
		(pad "1" smd circle
			(at -0.40005 0 270)
			(size 0 0)
			(layers "F.Cu" "F.Mask" "F.Paste")
			(net "SW_P0V8_PEX0_BOOT2")
		)
		(pad "2" smd circle
			(at 0.40005 0 270)
			(size 0 0)
			(layers "F.Cu" "F.Mask" "F.Paste")
			(net "SW_P0V8_PEX0_BOOT2_R")
		)
	)
	(footprint ""
		(layer "F.Cu")
		(at 375.18594 -343.952322 90)
		(property "Reference" "C781"
			(at 0 0 90)
			(layer "F.SilkS")
			(hide yes)
			(effects
				(font
					(size 1.27 1.27)
				)
			)
		)
		(property "Value" ""
			(at 0 0 90)
			(layer "F.Fab")
			(effects
				(font
					(size 1.27 1.27)
				)
			)
		)
		(duplicate_pad_numbers_are_jumpers no)
		(fp_line
			(start 0.299974 -0.150114)
			(end 0.299974 0.150114)
			(stroke
				(width 0.1)
				(type default)
			)
			(layer "F.Fab")
		)
		(fp_line
			(start -0.299974 -0.150114)
			(end 0.299974 -0.150114)
			(stroke
				(width 0.1)
				(type default)
			)
			(layer "F.Fab")
		)
		(fp_line
			(start 0.299974 0.150114)
			(end -0.299974 0.150114)
			(stroke
				(width 0.1)
				(type default)
			)
			(layer "F.Fab")
		)
		(fp_line
			(start -0.299974 0.150114)
			(end -0.299974 -0.150114)
			(stroke
				(width 0.1)
				(type default)
			)
			(layer "F.Fab")
		)
		(pad "1" smd rect
			(at -0.2667 0 90)
			(size 0.3048 0.381)
			(layers "F.Cu" "F.Mask" "F.Paste")
			(net "P5E_PEX3_STN6_TX_DN<102>")
		)
		(pad "2" smd rect
			(at 0.2667 0 90)
			(size 0.3048 0.381)
			(layers "F.Cu" "F.Mask" "F.Paste")
			(net "P5E_PEX3_STN6_TX_C_DN<102>")
		)
	)
	(footprint ""
		(layer "F.Cu")
		(at 359.156 -180.086 180)
		(property "Reference" "R4701"
			(at 0 0 180)
			(layer "F.SilkS")
			(hide yes)
			(effects
				(font
					(size 1.27 1.27)
				)
			)
		)
		(property "Value" ""
			(at 0 0 180)
			(layer "F.Fab")
			(effects
				(font
					(size 1.27 1.27)
				)
			)
		)
		(duplicate_pad_numbers_are_jumpers no)
		(fp_line
			(start 0.7874 0.4064)
			(end -0.7874 0.4064)
			(stroke
				(width 0.1524)
				(type default)
			)
			(layer "F.SilkS")
		)
		(fp_line
			(start 0.7874 -0.4064)
			(end 0.7874 0.4064)
			(stroke
				(width 0.1524)
				(type default)
			)
			(layer "F.SilkS")
		)
		(fp_line
			(start -0.7874 0.4064)
			(end -0.7874 -0.4064)
			(stroke
				(width 0.1524)
				(type default)
			)
			(layer "F.SilkS")
		)
		(fp_line
			(start -0.7874 -0.4064)
			(end 0.7874 -0.4064)
			(stroke
				(width 0.1524)
				(type default)
			)
			(layer "F.SilkS")
		)
		(fp_line
			(start 0.67945 0.3048)
			(end 0.120396 0.3048)
			(stroke
				(width 0.1)
				(type default)
			)
			(layer "F.Fab")
		)
		(fp_line
			(start 0.67945 -0.3048)
			(end 0.67945 0.3048)
			(stroke
				(width 0.1)
				(type default)
			)
			(layer "F.Fab")
		)
		(fp_line
			(start 0.12065 -0.2794)
			(end 0.12065 -0.3048)
			(stroke
				(width 0.1)
				(type default)
			)
			(layer "F.Fab")
		)
		(fp_line
			(start 0.12065 -0.3048)
			(end 0.67945 -0.3048)
			(stroke
				(width 0.1)
				(type default)
			)
			(layer "F.Fab")
		)
		(fp_line
			(start 0.120396 0.3048)
			(end 0.120396 0.2794)
			(stroke
				(width 0.1)
				(type default)
			)
			(layer "F.Fab")
		)
		(fp_line
			(start 0.120396 0.2794)
			(end -0.12065 0.2794)
			(stroke
				(width 0.1)
				(type default)
			)
			(layer "F.Fab")
		)
		(fp_line
			(start -0.12065 0.3048)
			(end -0.67945 0.3048)
			(stroke
				(width 0.1)
				(type default)
			)
			(layer "F.Fab")
		)
		(fp_line
			(start -0.12065 0.2794)
			(end -0.12065 0.3048)
			(stroke
				(width 0.1)
				(type default)
			)
			(layer "F.Fab")
		)
		(fp_line
			(start -0.12065 -0.2794)
			(end 0.12065 -0.2794)
			(stroke
				(width 0.1)
				(type default)
			)
			(layer "F.Fab")
		)
		(fp_line
			(start -0.12065 -0.305054)
			(end -0.12065 -0.2794)
			(stroke
				(width 0.1)
				(type default)
			)
			(layer "F.Fab")
		)
		(fp_line
			(start -0.67945 0.3048)
			(end -0.67945 -0.305054)
			(stroke
				(width 0.1)
				(type default)
			)
			(layer "F.Fab")
		)
		(fp_line
			(start -0.67945 -0.305054)
			(end -0.12065 -0.305054)
			(stroke
				(width 0.1)
				(type default)
			)
			(layer "F.Fab")
		)
		(pad "1" smd circle
			(at -0.40005 0 180)
			(size 0 0)
			(layers "F.Cu" "F.Mask" "F.Paste")
			(net "PCA9555_1_PEX1_A2")
		)
		(pad "2" smd circle
			(at 0.40005 0 180)
			(size 0 0)
			(layers "F.Cu" "F.Mask" "F.Paste")
			(net "P3V3_AUX")
		)
	)
	(footprint ""
		(layer "F.Cu")
		(at 415.442654 -70.844918 -90)
		(property "Reference" "PD47"
			(at 4.093718 2.183384 90)
			(unlocked yes)
			(layer "F.SilkS")
			(effects
				(font
					(size 0.7874 0.5842)
					(thickness 0.1524)
				)
				(justify left)
			)
		)
		(property "Value" ""
			(at 0 0 270)
			(layer "F.Fab")
			(effects
				(font
					(size 1.27 1.27)
				)
			)
		)
		(duplicate_pad_numbers_are_jumpers no)
		(fp_line
			(start -3.400044 1.459992)
			(end -3.400044 -1.459992)
			(stroke
				(width 0.1524)
				(type default)
			)
			(layer "F.SilkS")
		)
		(fp_line
			(start 4.107942 1.459992)
			(end -3.400044 1.459992)
			(stroke
				(width 0.1524)
				(type default)
			)
			(layer "F.SilkS")
		)
		(fp_line
			(start -3.400044 -1.459992)
			(end 4.107942 -1.459992)
			(stroke
				(width 0.1524)
				(type default)
			)
			(layer "F.SilkS")
		)
		(fp_line
			(start 4.107942 -1.459992)
			(end 4.107942 1.459992)
			(stroke
				(width 0.1524)
				(type default)
			)
			(layer "F.SilkS")
		)
		(fp_poly
			(pts
				(xy 4.107942 -1.459992) (xy 4.107942 1.459992) (xy 3.308096 1.459992) (xy 3.308096 -1.459992)
			)
			(stroke
				(width 0)
				(type default)
			)
			(fill yes)
			(layer "F.SilkS")
		)
		(fp_line
			(start -2.29997 1.459992)
			(end -2.29997 -1.459992)
			(stroke
				(width 0.1)
				(type default)
			)
			(layer "F.Fab")
		)
		(fp_line
			(start 2.29997 1.459992)
			(end -2.29997 1.459992)
			(stroke
				(width 0.1)
				(type default)
			)
			(layer "F.Fab")
		)
		(fp_line
			(start -2.29997 -1.459992)
			(end 2.29997 -1.459992)
			(stroke
				(width 0.1)
				(type default)
			)
			(layer "F.Fab")
		)
		(fp_line
			(start 2.29997 -1.459992)
			(end 2.29997 1.459992)
			(stroke
				(width 0.1)
				(type default)
			)
			(layer "F.Fab")
		)
		(fp_text user "-"
			(at 5.4102 0.29845 90)
			(unlocked yes)
			(layer "F.SilkS")
			(effects
				(font
					(size 1.905 1.4224)
					(thickness 0.1524)
				)
				(justify left)
			)
		)
		(fp_text user "+"
			(at -5.184648 -0.258318 270)
			(unlocked yes)
			(layer "F.SilkS")
			(effects
				(font
					(size 1.905 1.4224)
					(thickness 0.1524)
				)
				(justify left)
			)
		)
		(fp_text user "-"
			(at 5.4102 0.29845 90)
			(unlocked yes)
			(layer "F.Fab")
			(effects
				(font
					(size 1.905 1.4224)
					(thickness 0.1524)
				)
				(justify left)
			)
		)
		(fp_text user "+"
			(at -4.7752 -0.12065 270)
			(unlocked yes)
			(layer "F.Fab")
			(effects
				(font
					(size 1.905 1.4224)
					(thickness 0.1524)
				)
				(justify left)
			)
		)
		(pad "A" smd rect
			(at -1.999996 0)
			(size 1.7018 2.5146)
			(layers "F.Cu" "F.Mask" "F.Paste")
			(net "GND")
		)
		(pad "C" smd rect
			(at 1.999996 0)
			(size 1.7018 2.5146)
			(layers "F.Cu" "F.Mask" "F.Paste")
			(net "P12V_SSD14_R")
		)
	)
	(footprint ""
		(layer "F.Cu")
		(at 98.434398 -30.94609 180)
		(property "Reference" "C93"
			(at 0 0 180)
			(layer "F.SilkS")
			(hide yes)
			(effects
				(font
					(size 1.27 1.27)
				)
			)
		)
		(property "Value" ""
			(at 0 0 180)
			(layer "F.Fab")
			(effects
				(font
					(size 1.27 1.27)
				)
			)
		)
		(duplicate_pad_numbers_are_jumpers no)
		(fp_line
			(start 0.299974 0.150114)
			(end -0.299974 0.150114)
			(stroke
				(width 0.1)
				(type default)
			)
			(layer "F.Fab")
		)
		(fp_line
			(start 0.299974 -0.150114)
			(end 0.299974 0.150114)
			(stroke
				(width 0.1)
				(type default)
			)
			(layer "F.Fab")
		)
		(fp_line
			(start -0.299974 0.150114)
			(end -0.299974 -0.150114)
			(stroke
				(width 0.1)
				(type default)
			)
			(layer "F.Fab")
		)
		(fp_line
			(start -0.299974 -0.150114)
			(end 0.299974 -0.150114)
			(stroke
				(width 0.1)
				(type default)
			)
			(layer "F.Fab")
		)
		(pad "1" smd rect
			(at -0.2667 0 180)
			(size 0.3048 0.381)
			(layers "F.Cu" "F.Mask" "F.Paste")
			(net "P5E_PEX0_STN2_TX_DP<33>")
		)
		(pad "2" smd rect
			(at 0.2667 0 180)
			(size 0.3048 0.381)
			(layers "F.Cu" "F.Mask" "F.Paste")
			(net "P5E_PEX0_STN2_TX_C_DP<33>")
		)
	)
	(footprint ""
		(layer "F.Cu")
		(at 358.41051 -122.931428 180)
		(property "Reference" "PC480"
			(at 0 0 180)
			(layer "F.SilkS")
			(hide yes)
			(effects
				(font
					(size 1.27 1.27)
				)
			)
		)
		(property "Value" ""
			(at 0 0 180)
			(layer "F.Fab")
			(effects
				(font
					(size 1.27 1.27)
				)
			)
		)
		(duplicate_pad_numbers_are_jumpers no)
		(fp_line
			(start 0.7874 0.4064)
			(end -0.7874 0.4064)
			(stroke
				(width 0.1524)
				(type default)
			)
			(layer "F.SilkS")
		)
		(fp_line
			(start 0.7874 -0.4064)
			(end 0.7874 0.4064)
			(stroke
				(width 0.1524)
				(type default)
			)
			(layer "F.SilkS")
		)
		(fp_line
			(start -0.7874 0.4064)
			(end -0.7874 -0.4064)
			(stroke
				(width 0.1524)
				(type default)
			)
			(layer "F.SilkS")
		)
		(fp_line
			(start -0.7874 -0.4064)
			(end 0.7874 -0.4064)
			(stroke
				(width 0.1524)
				(type default)
			)
			(layer "F.SilkS")
		)
		(fp_line
			(start 0.67945 0.3048)
			(end 0.120396 0.3048)
			(stroke
				(width 0.1)
				(type default)
			)
			(layer "F.Fab")
		)
		(fp_line
			(start 0.67945 -0.3048)
			(end 0.67945 0.3048)
			(stroke
				(width 0.1)
				(type default)
			)
			(layer "F.Fab")
		)
		(fp_line
			(start 0.12065 -0.2794)
			(end 0.12065 -0.3048)
			(stroke
				(width 0.1)
				(type default)
			)
			(layer "F.Fab")
		)
		(fp_line
			(start 0.12065 -0.3048)
			(end 0.67945 -0.3048)
			(stroke
				(width 0.1)
				(type default)
			)
			(layer "F.Fab")
		)
		(fp_line
			(start 0.120396 0.3048)
			(end 0.120396 0.2794)
			(stroke
				(width 0.1)
				(type default)
			)
			(layer "F.Fab")
		)
		(fp_line
			(start 0.120396 0.2794)
			(end -0.12065 0.2794)
			(stroke
				(width 0.1)
				(type default)
			)
			(layer "F.Fab")
		)
		(fp_line
			(start -0.12065 0.3048)
			(end -0.67945 0.3048)
			(stroke
				(width 0.1)
				(type default)
			)
			(layer "F.Fab")
		)
		(fp_line
			(start -0.12065 0.2794)
			(end -0.12065 0.3048)
			(stroke
				(width 0.1)
				(type default)
			)
			(layer "F.Fab")
		)
		(fp_line
			(start -0.12065 -0.2794)
			(end 0.12065 -0.2794)
			(stroke
				(width 0.1)
				(type default)
			)
			(layer "F.Fab")
		)
		(fp_line
			(start -0.12065 -0.305054)
			(end -0.12065 -0.2794)
			(stroke
				(width 0.1)
				(type default)
			)
			(layer "F.Fab")
		)
		(fp_line
			(start -0.67945 0.3048)
			(end -0.67945 -0.305054)
			(stroke
				(width 0.1)
				(type default)
			)
			(layer "F.Fab")
		)
		(fp_line
			(start -0.67945 -0.305054)
			(end -0.12065 -0.305054)
			(stroke
				(width 0.1)
				(type default)
			)
			(layer "F.Fab")
		)
		(pad "1" smd circle
			(at -0.40005 0 180)
			(size 0 0)
			(layers "F.Cu" "F.Mask" "F.Paste")
			(net "P5V_AUX")
		)
		(pad "2" smd circle
			(at 0.40005 0 180)
			(size 0 0)
			(layers "F.Cu" "F.Mask" "F.Paste")
			(net "GND")
		)
	)
	(footprint ""
		(layer "F.Cu")
		(at 185.97118 -412.39186 90)
		(property "Reference" "R498"
			(at 0 0 90)
			(layer "F.SilkS")
			(hide yes)
			(effects
				(font
					(size 1.27 1.27)
				)
			)
		)
		(property "Value" ""
			(at 0 0 90)
			(layer "F.Fab")
			(effects
				(font
					(size 1.27 1.27)
				)
			)
		)
		(duplicate_pad_numbers_are_jumpers no)
		(fp_line
			(start 0.7874 -0.4064)
			(end 0.7874 0.4064)
			(stroke
				(width 0.1524)
				(type default)
			)
			(layer "F.SilkS")
		)
		(fp_line
			(start -0.7874 -0.4064)
			(end 0.7874 -0.4064)
			(stroke
				(width 0.1524)
				(type default)
			)
			(layer "F.SilkS")
		)
		(fp_line
			(start 0.7874 0.4064)
			(end -0.7874 0.4064)
			(stroke
				(width 0.1524)
				(type default)
			)
			(layer "F.SilkS")
		)
		(fp_line
			(start -0.7874 0.4064)
			(end -0.7874 -0.4064)
			(stroke
				(width 0.1524)
				(type default)
			)
			(layer "F.SilkS")
		)
		(fp_line
			(start -0.12065 -0.305054)
			(end -0.12065 -0.2794)
			(stroke
				(width 0.1)
				(type default)
			)
			(layer "F.Fab")
		)
		(fp_line
			(start -0.67945 -0.305054)
			(end -0.12065 -0.305054)
			(stroke
				(width 0.1)
				(type default)
			)
			(layer "F.Fab")
		)
		(fp_line
			(start 0.67945 -0.3048)
			(end 0.67945 0.3048)
			(stroke
				(width 0.1)
				(type default)
			)
			(layer "F.Fab")
		)
		(fp_line
			(start 0.12065 -0.3048)
			(end 0.67945 -0.3048)
			(stroke
				(width 0.1)
				(type default)
			)
			(layer "F.Fab")
		)
		(fp_line
			(start 0.12065 -0.2794)
			(end 0.12065 -0.3048)
			(stroke
				(width 0.1)
				(type default)
			)
			(layer "F.Fab")
		)
		(fp_line
			(start -0.12065 -0.2794)
			(end 0.12065 -0.2794)
			(stroke
				(width 0.1)
				(type default)
			)
			(layer "F.Fab")
		)
		(fp_line
			(start 0.120396 0.2794)
			(end -0.12065 0.2794)
			(stroke
				(width 0.1)
				(type default)
			)
			(layer "F.Fab")
		)
		(fp_line
			(start -0.12065 0.2794)
			(end -0.12065 0.3048)
			(stroke
				(width 0.1)
				(type default)
			)
			(layer "F.Fab")
		)
		(fp_line
			(start 0.67945 0.3048)
			(end 0.120396 0.3048)
			(stroke
				(width 0.1)
				(type default)
			)
			(layer "F.Fab")
		)
		(fp_line
			(start 0.120396 0.3048)
			(end 0.120396 0.2794)
			(stroke
				(width 0.1)
				(type default)
			)
			(layer "F.Fab")
		)
		(fp_line
			(start -0.12065 0.3048)
			(end -0.67945 0.3048)
			(stroke
				(width 0.1)
				(type default)
			)
			(layer "F.Fab")
		)
		(fp_line
			(start -0.67945 0.3048)
			(end -0.67945 -0.305054)
			(stroke
				(width 0.1)
				(type default)
			)
			(layer "F.Fab")
		)
		(pad "1" smd circle
			(at -0.40005 0 90)
			(size 0 0)
			(layers "F.Cu" "F.Mask" "F.Paste")
			(net "HSC_UV_N")
		)
		(pad "2" smd circle
			(at 0.40005 0 90)
			(size 0 0)
			(layers "F.Cu" "F.Mask" "F.Paste")
			(net "HSC_UV_R_N")
		)
	)
)
